(kicad_pcb
	(version 20260206)
	(generator "pcbnew")
	(generator_version "10.0")
	(general
		(thickness 1.6)
		(legacy_teardrops no)
	)
	(paper "A4")
	(title_block
		(title "12092022_DA0F0TFB6D0_F0T_FAN_BOARD_MP5048_D_brd_v02_OCP.brd")
		(comment 1 "Grand Teton / footprints 626-632 of 924")
	)
	(layers
		(0 "F.Cu" signal "TOP")
		(4 "In1.Cu" signal "GND")
		(6 "In2.Cu" signal "IN1")
		(8 "In3.Cu" signal "IN2")
		(10 "In4.Cu" signal "GND1")
		(2 "B.Cu" signal "BOTTOM")
		(9 "F.Adhes" user "F.Adhesive")
		(11 "B.Adhes" user "B.Adhesive")
		(13 "F.Paste" user "Package Geometry/Pastemask Top")
		(15 "B.Paste" user "Package Geometry/Pastemask Bottom")
		(5 "F.SilkS" user "Ref Des/Silkscreen Top")
		(7 "B.SilkS" user "Ref Des/Silkscreen Bottom")
		(1 "F.Mask" user "Board Geometry/Soldermask Top")
		(3 "B.Mask" user "Board Geometry/Soldermask Bottom")
		(17 "Dwgs.User" user "User.Drawings")
		(19 "Cmts.User" user "User.Comments")
		(21 "Eco1.User" user "User.Eco1")
		(23 "Eco2.User" user "User.Eco2")
		(25 "Edge.Cuts" user "Board Geometry/Outline")
		(27 "Margin" user)
		(31 "F.CrtYd" user "Package Geometry/Place Bound Top")
		(29 "B.CrtYd" user "Package Geometry/Place Bound Bottom")
		(35 "F.Fab" user "Ref Des/Assembly Top")
		(33 "B.Fab" user "Ref Des/Assembly Bottom")
	)
	(footprint ""
		(layer "F.Cu")
		(at 37.338 -204.752956 180)
		(property "Reference" "R5204"
			(at 0 0 180)
			(layer "F.SilkS")
			(hide yes)
			(effects
				(font
					(size 1.27 1.27)
				)
			)
		)
		(property "Value" ""
			(at 0 0 180)
			(layer "F.Fab")
			(effects
				(font
					(size 1.27 1.27)
				)
			)
		)
		(duplicate_pad_numbers_are_jumpers no)
		(fp_line
			(start 0.7874 0.4064)
			(end -0.7874 0.4064)
			(stroke
				(width 0.1524)
				(type default)
			)
			(layer "F.SilkS")
		)
		(fp_line
			(start 0.7874 -0.4064)
			(end 0.7874 0.4064)
			(stroke
				(width 0.1524)
				(type default)
			)
			(layer "F.SilkS")
		)
		(fp_line
			(start -0.7874 0.4064)
			(end -0.7874 -0.4064)
			(stroke
				(width 0.1524)
				(type default)
			)
			(layer "F.SilkS")
		)
		(fp_line
			(start -0.7874 -0.4064)
			(end 0.7874 -0.4064)
			(stroke
				(width 0.1524)
				(type default)
			)
			(layer "F.SilkS")
		)
		(fp_line
			(start 0.67945 0.3048)
			(end 0.120396 0.3048)
			(stroke
				(width 0.1)
				(type default)
			)
			(layer "F.Fab")
		)
		(fp_line
			(start 0.67945 -0.3048)
			(end 0.67945 0.3048)
			(stroke
				(width 0.1)
				(type default)
			)
			(layer "F.Fab")
		)
		(fp_line
			(start 0.12065 -0.2794)
			(end 0.12065 -0.3048)
			(stroke
				(width 0.1)
				(type default)
			)
			(layer "F.Fab")
		)
		(fp_line
			(start 0.12065 -0.3048)
			(end 0.67945 -0.3048)
			(stroke
				(width 0.1)
				(type default)
			)
			(layer "F.Fab")
		)
		(fp_line
			(start 0.120396 0.3048)
			(end 0.120396 0.2794)
			(stroke
				(width 0.1)
				(type default)
			)
			(layer "F.Fab")
		)
		(fp_line
			(start 0.120396 0.2794)
			(end -0.12065 0.2794)
			(stroke
				(width 0.1)
				(type default)
			)
			(layer "F.Fab")
		)
		(fp_line
			(start -0.12065 0.3048)
			(end -0.67945 0.3048)
			(stroke
				(width 0.1)
				(type default)
			)
			(layer "F.Fab")
		)
		(fp_line
			(start -0.12065 0.2794)
			(end -0.12065 0.3048)
			(stroke
				(width 0.1)
				(type default)
			)
			(layer "F.Fab")
		)
		(fp_line
			(start -0.12065 -0.2794)
			(end 0.12065 -0.2794)
			(stroke
				(width 0.1)
				(type default)
			)
			(layer "F.Fab")
		)
		(fp_line
			(start -0.12065 -0.305054)
			(end -0.12065 -0.2794)
			(stroke
				(width 0.1)
				(type default)
			)
			(layer "F.Fab")
		)
		(fp_line
			(start -0.67945 0.3048)
			(end -0.67945 -0.305054)
			(stroke
				(width 0.1)
				(type default)
			)
			(layer "F.Fab")
		)
		(fp_line
			(start -0.67945 -0.305054)
			(end -0.12065 -0.305054)
			(stroke
				(width 0.1)
				(type default)
			)
			(layer "F.Fab")
		)
		(pad "1" smd circle
			(at -0.40005 0 180)
			(size 0 0)
			(layers "F.Cu" "F.Mask" "F.Paste")
			(net "SMB_FAN1_SDA_R")
		)
		(pad "2" smd circle
			(at 0.40005 0 180)
			(size 0 0)
			(layers "F.Cu" "F.Mask" "F.Paste")
			(net "SMB_FAN1_SDA")
		)
	)
	(footprint ""
		(layer "F.Cu")
		(at 30.353 -178.816)
		(property "Reference" "R511"
			(at 0 0 0)
			(layer "F.SilkS")
			(hide yes)
			(effects
				(font
					(size 1.27 1.27)
				)
			)
		)
		(property "Value" ""
			(at 0 0 0)
			(layer "F.Fab")
			(effects
				(font
					(size 1.27 1.27)
				)
			)
		)
		(duplicate_pad_numbers_are_jumpers no)
		(fp_line
			(start -0.7874 -0.4064)
			(end 0.7874 -0.4064)
			(stroke
				(width 0.1524)
				(type default)
			)
			(layer "F.SilkS")
		)
		(fp_line
			(start -0.7874 0.4064)
			(end -0.7874 -0.4064)
			(stroke
				(width 0.1524)
				(type default)
			)
			(layer "F.SilkS")
		)
		(fp_line
			(start 0.7874 -0.4064)
			(end 0.7874 0.4064)
			(stroke
				(width 0.1524)
				(type default)
			)
			(layer "F.SilkS")
		)
		(fp_line
			(start 0.7874 0.4064)
			(end -0.7874 0.4064)
			(stroke
				(width 0.1524)
				(type default)
			)
			(layer "F.SilkS")
		)
		(fp_line
			(start -0.67945 -0.305054)
			(end -0.12065 -0.305054)
			(stroke
				(width 0.1)
				(type default)
			)
			(layer "F.Fab")
		)
		(fp_line
			(start -0.67945 0.3048)
			(end -0.67945 -0.305054)
			(stroke
				(width 0.1)
				(type default)
			)
			(layer "F.Fab")
		)
		(fp_line
			(start -0.12065 -0.305054)
			(end -0.12065 -0.2794)
			(stroke
				(width 0.1)
				(type default)
			)
			(layer "F.Fab")
		)
		(fp_line
			(start -0.12065 -0.2794)
			(end 0.12065 -0.2794)
			(stroke
				(width 0.1)
				(type default)
			)
			(layer "F.Fab")
		)
		(fp_line
			(start -0.12065 0.2794)
			(end -0.12065 0.3048)
			(stroke
				(width 0.1)
				(type default)
			)
			(layer "F.Fab")
		)
		(fp_line
			(start -0.12065 0.3048)
			(end -0.67945 0.3048)
			(stroke
				(width 0.1)
				(type default)
			)
			(layer "F.Fab")
		)
		(fp_line
			(start 0.120396 0.2794)
			(end -0.12065 0.2794)
			(stroke
				(width 0.1)
				(type default)
			)
			(layer "F.Fab")
		)
		(fp_line
			(start 0.120396 0.3048)
			(end 0.120396 0.2794)
			(stroke
				(width 0.1)
				(type default)
			)
			(layer "F.Fab")
		)
		(fp_line
			(start 0.12065 -0.3048)
			(end 0.67945 -0.3048)
			(stroke
				(width 0.1)
				(type default)
			)
			(layer "F.Fab")
		)
		(fp_line
			(start 0.12065 -0.2794)
			(end 0.12065 -0.3048)
			(stroke
				(width 0.1)
				(type default)
			)
			(layer "F.Fab")
		)
		(fp_line
			(start 0.67945 -0.3048)
			(end 0.67945 0.3048)
			(stroke
				(width 0.1)
				(type default)
			)
			(layer "F.Fab")
		)
		(fp_line
			(start 0.67945 0.3048)
			(end 0.120396 0.3048)
			(stroke
				(width 0.1)
				(type default)
			)
			(layer "F.Fab")
		)
		(pad "1" smd circle
			(at -0.40005 0)
			(size 0 0)
			(layers "F.Cu" "F.Mask" "F.Paste")
			(net "P3V3_AUX")
		)
		(pad "2" smd circle
			(at 0.40005 0)
			(size 0 0)
			(layers "F.Cu" "F.Mask" "F.Paste")
			(net "P52V_FAN_2_BUFF_EN")
		)
	)
	(footprint ""
		(layer "F.Cu")
		(at 22.225 -34.163 -90)
		(property "Reference" "R5658"
			(at 0 0 270)
			(layer "F.SilkS")
			(hide yes)
			(effects
				(font
					(size 1.27 1.27)
				)
			)
		)
		(property "Value" ""
			(at 0 0 270)
			(layer "F.Fab")
			(effects
				(font
					(size 1.27 1.27)
				)
			)
		)
		(duplicate_pad_numbers_are_jumpers no)
		(fp_line
			(start -0.7874 0.4064)
			(end -0.7874 -0.4064)
			(stroke
				(width 0.1524)
				(type default)
			)
			(layer "F.SilkS")
		)
		(fp_line
			(start 0.7874 0.4064)
			(end -0.7874 0.4064)
			(stroke
				(width 0.1524)
				(type default)
			)
			(layer "F.SilkS")
		)
		(fp_line
			(start -0.7874 -0.4064)
			(end 0.7874 -0.4064)
			(stroke
				(width 0.1524)
				(type default)
			)
			(layer "F.SilkS")
		)
		(fp_line
			(start 0.7874 -0.4064)
			(end 0.7874 0.4064)
			(stroke
				(width 0.1524)
				(type default)
			)
			(layer "F.SilkS")
		)
		(fp_line
			(start -0.67945 0.3048)
			(end -0.67945 -0.305054)
			(stroke
				(width 0.1)
				(type default)
			)
			(layer "F.Fab")
		)
		(fp_line
			(start -0.12065 0.3048)
			(end -0.67945 0.3048)
			(stroke
				(width 0.1)
				(type default)
			)
			(layer "F.Fab")
		)
		(fp_line
			(start 0.120396 0.3048)
			(end 0.120396 0.2794)
			(stroke
				(width 0.1)
				(type default)
			)
			(layer "F.Fab")
		)
		(fp_line
			(start 0.67945 0.3048)
			(end 0.120396 0.3048)
			(stroke
				(width 0.1)
				(type default)
			)
			(layer "F.Fab")
		)
		(fp_line
			(start -0.12065 0.2794)
			(end -0.12065 0.3048)
			(stroke
				(width 0.1)
				(type default)
			)
			(layer "F.Fab")
		)
		(fp_line
			(start 0.120396 0.2794)
			(end -0.12065 0.2794)
			(stroke
				(width 0.1)
				(type default)
			)
			(layer "F.Fab")
		)
		(fp_line
			(start -0.12065 -0.2794)
			(end 0.12065 -0.2794)
			(stroke
				(width 0.1)
				(type default)
			)
			(layer "F.Fab")
		)
		(fp_line
			(start 0.12065 -0.2794)
			(end 0.12065 -0.3048)
			(stroke
				(width 0.1)
				(type default)
			)
			(layer "F.Fab")
		)
		(fp_line
			(start 0.12065 -0.3048)
			(end 0.67945 -0.3048)
			(stroke
				(width 0.1)
				(type default)
			)
			(layer "F.Fab")
		)
		(fp_line
			(start 0.67945 -0.3048)
			(end 0.67945 0.3048)
			(stroke
				(width 0.1)
				(type default)
			)
			(layer "F.Fab")
		)
		(fp_line
			(start -0.67945 -0.305054)
			(end -0.12065 -0.305054)
			(stroke
				(width 0.1)
				(type default)
			)
			(layer "F.Fab")
		)
		(fp_line
			(start -0.12065 -0.305054)
			(end -0.12065 -0.2794)
			(stroke
				(width 0.1)
				(type default)
			)
			(layer "F.Fab")
		)
		(pad "1" smd rect
			(at -0.40005 0 90)
			(size 0.4572 0.508)
			(layers "F.Cu" "F.Mask" "F.Paste")
			(net "P12V_LED")
		)
		(pad "2" smd rect
			(at 0.40005 0 90)
			(size 0.4572 0.508)
			(layers "F.Cu" "F.Mask" "F.Paste")
			(net "U409_D1")
		)
	)
	(footprint ""
		(layer "F.Cu")
		(at 34.544 -105.791)
		(property "Reference" "U372"
			(at -2.74955 3.17246 90)
			(unlocked yes)
			(layer "F.SilkS")
			(effects
				(font
					(size 0.7874 0.5842)
					(thickness 0.1524)
				)
				(justify left)
			)
		)
		(property "Value" ""
			(at 0 0 0)
			(layer "F.Fab")
			(effects
				(font
					(size 1.27 1.27)
				)
			)
		)
		(duplicate_pad_numbers_are_jumpers no)
		(fp_line
			(start -1.335278 -1.100074)
			(end -1.335278 1.100074)
			(stroke
				(width 0.1524)
				(type default)
			)
			(layer "F.SilkS")
		)
		(fp_line
			(start -1.335278 1.100074)
			(end 1.335278 1.100074)
			(stroke
				(width 0.1524)
				(type default)
			)
			(layer "F.SilkS")
		)
		(fp_line
			(start 1.335278 -1.100074)
			(end -1.335278 -1.100074)
			(stroke
				(width 0.1524)
				(type default)
			)
			(layer "F.SilkS")
		)
		(fp_line
			(start 1.335278 1.100074)
			(end 1.335278 -1.100074)
			(stroke
				(width 0.1524)
				(type default)
			)
			(layer "F.SilkS")
		)
		(fp_line
			(start -0.674878 -1.100074)
			(end -0.674878 1.100074)
			(stroke
				(width 0.1)
				(type default)
			)
			(layer "F.Fab")
		)
		(fp_line
			(start -0.674878 1.100074)
			(end 0.674878 1.100074)
			(stroke
				(width 0.1)
				(type default)
			)
			(layer "F.Fab")
		)
		(fp_line
			(start 0.674878 -1.100074)
			(end -0.674878 -1.100074)
			(stroke
				(width 0.1)
				(type default)
			)
			(layer "F.Fab")
		)
		(fp_line
			(start 0.674878 1.100074)
			(end 0.674878 -1.100074)
			(stroke
				(width 0.1)
				(type default)
			)
			(layer "F.Fab")
		)
		(pad "D" smd rect
			(at 0.8001 0 270)
			(size 0.6096 0.8128)
			(layers "F.Cu" "F.Mask" "F.Paste")
			(net "FAN_2_OK_LED_R_N")
		)
		(pad "G" smd rect
			(at -0.8001 -0.649986 270)
			(size 0.6096 0.8128)
			(layers "F.Cu" "F.Mask" "F.Paste")
			(net "FAN_2_OK_R_LED")
		)
		(pad "S" smd rect
			(at -0.8001 0.649986 270)
			(size 0.6096 0.8128)
			(layers "F.Cu" "F.Mask" "F.Paste")
			(net "GND")
		)
	)
	(footprint ""
		(layer "F.Cu")
		(at 14.351 -300.736 180)
		(property "Reference" "D258"
			(at 4.064 -1.04267 0)
			(unlocked yes)
			(layer "F.SilkS")
			(effects
				(font
					(size 0.7874 0.5842)
					(thickness 0.1524)
				)
				(justify left)
			)
		)
		(property "Value" ""
			(at 0 0 180)
			(layer "F.Fab")
			(effects
				(font
					(size 1.27 1.27)
				)
			)
		)
		(duplicate_pad_numbers_are_jumpers no)
		(fp_line
			(start 0.94488 0.450088)
			(end 0.94488 -0.450088)
			(stroke
				(width 0.1524)
				(type default)
			)
			(layer "F.SilkS")
		)
		(fp_line
			(start 0.94488 -0.450088)
			(end -0.854964 -0.450088)
			(stroke
				(width 0.1524)
				(type default)
			)
			(layer "F.SilkS")
		)
		(fp_line
			(start 0.870458 -0.2794)
			(end 0.845058 0.4064)
			(stroke
				(width 0.1524)
				(type default)
			)
			(layer "F.SilkS")
		)
		(fp_line
			(start 0.845058 0.4064)
			(end 0.845058 -0.381)
			(stroke
				(width 0.1524)
				(type default)
			)
			(layer "F.SilkS")
		)
		(fp_line
			(start -0.854964 0.450088)
			(end 0.925068 0.450088)
			(stroke
				(width 0.1524)
				(type default)
			)
			(layer "F.SilkS")
		)
		(fp_line
			(start -0.854964 -0.450088)
			(end -0.854964 0.450088)
			(stroke
				(width 0.1524)
				(type default)
			)
			(layer "F.SilkS")
		)
		(fp_line
			(start 0.54991 0.350012)
			(end 0.54991 -0.350012)
			(stroke
				(width 0.1)
				(type default)
			)
			(layer "F.Fab")
		)
		(fp_line
			(start 0.54991 -0.350012)
			(end -0.54991 -0.350012)
			(stroke
				(width 0.1)
				(type default)
			)
			(layer "F.Fab")
		)
		(fp_line
			(start -0.54991 0.350012)
			(end 0.54991 0.350012)
			(stroke
				(width 0.1)
				(type default)
			)
			(layer "F.Fab")
		)
		(fp_line
			(start -0.54991 -0.350012)
			(end -0.54991 0.350012)
			(stroke
				(width 0.1)
				(type default)
			)
			(layer "F.Fab")
		)
		(fp_text user "-"
			(at 2.159 0.22225 0)
			(unlocked yes)
			(layer "F.SilkS")
			(effects
				(font
					(size 1.905 1.4224)
					(thickness 0.1524)
				)
				(justify left)
			)
		)
		(fp_text user "+"
			(at -0.66802 -0.50927 0)
			(unlocked yes)
			(layer "F.SilkS")
			(effects
				(font
					(size 1.905 1.4224)
					(thickness 0.1524)
				)
				(justify left)
			)
		)
		(fp_text user "-"
			(at 2.48539 0.239014 0)
			(unlocked yes)
			(layer "F.Fab")
			(effects
				(font
					(size 1.905 1.4224)
					(thickness 0.1524)
				)
				(justify left)
			)
		)
		(fp_text user "+"
			(at -0.808228 0.239014 0)
			(unlocked yes)
			(layer "F.Fab")
			(effects
				(font
					(size 1.905 1.4224)
					(thickness 0.1524)
				)
				(justify left)
			)
		)
		(pad "A" smd rect
			(at -0.424942 0 180)
			(size 0.5588 0.6096)
			(layers "F.Cu" "F.Mask" "F.Paste")
			(net "GND")
		)
		(pad "C" smd rect
			(at 0.424942 0)
			(size 0.5588 0.6096)
			(layers "F.Cu" "F.Mask" "F.Paste")
			(net "FAN_7_OK_R_LED_N")
		)
	)
	(footprint ""
		(layer "F.Cu")
		(at 36.703 -65.278)
		(property "Reference" "PR21"
			(at 0 0 0)
			(layer "F.SilkS")
			(hide yes)
			(effects
				(font
					(size 1.27 1.27)
				)
			)
		)
		(property "Value" ""
			(at 0 0 0)
			(layer "F.Fab")
			(effects
				(font
					(size 1.27 1.27)
				)
			)
		)
		(duplicate_pad_numbers_are_jumpers no)
		(fp_line
			(start -0.7874 -0.4064)
			(end 0.7874 -0.4064)
			(stroke
				(width 0.1524)
				(type default)
			)
			(layer "F.SilkS")
		)
		(fp_line
			(start -0.7874 0.4064)
			(end -0.7874 -0.4064)
			(stroke
				(width 0.1524)
				(type default)
			)
			(layer "F.SilkS")
		)
		(fp_line
			(start 0.7874 -0.4064)
			(end 0.7874 0.4064)
			(stroke
				(width 0.1524)
				(type default)
			)
			(layer "F.SilkS")
		)
		(fp_line
			(start 0.7874 0.4064)
			(end -0.7874 0.4064)
			(stroke
				(width 0.1524)
				(type default)
			)
			(layer "F.SilkS")
		)
		(fp_line
			(start -0.67945 -0.305054)
			(end -0.12065 -0.305054)
			(stroke
				(width 0.1)
				(type default)
			)
			(layer "F.Fab")
		)
		(fp_line
			(start -0.67945 0.3048)
			(end -0.67945 -0.305054)
			(stroke
				(width 0.1)
				(type default)
			)
			(layer "F.Fab")
		)
		(fp_line
			(start -0.12065 -0.305054)
			(end -0.12065 -0.2794)
			(stroke
				(width 0.1)
				(type default)
			)
			(layer "F.Fab")
		)
		(fp_line
			(start -0.12065 -0.2794)
			(end 0.12065 -0.2794)
			(stroke
				(width 0.1)
				(type default)
			)
			(layer "F.Fab")
		)
		(fp_line
			(start -0.12065 0.2794)
			(end -0.12065 0.3048)
			(stroke
				(width 0.1)
				(type default)
			)
			(layer "F.Fab")
		)
		(fp_line
			(start -0.12065 0.3048)
			(end -0.67945 0.3048)
			(stroke
				(width 0.1)
				(type default)
			)
			(layer "F.Fab")
		)
		(fp_line
			(start 0.120396 0.2794)
			(end -0.12065 0.2794)
			(stroke
				(width 0.1)
				(type default)
			)
			(layer "F.Fab")
		)
		(fp_line
			(start 0.120396 0.3048)
			(end 0.120396 0.2794)
			(stroke
				(width 0.1)
				(type default)
			)
			(layer "F.Fab")
		)
		(fp_line
			(start 0.12065 -0.3048)
			(end 0.67945 -0.3048)
			(stroke
				(width 0.1)
				(type default)
			)
			(layer "F.Fab")
		)
		(fp_line
			(start 0.12065 -0.2794)
			(end 0.12065 -0.3048)
			(stroke
				(width 0.1)
				(type default)
			)
			(layer "F.Fab")
		)
		(fp_line
			(start 0.67945 -0.3048)
			(end 0.67945 0.3048)
			(stroke
				(width 0.1)
				(type default)
			)
			(layer "F.Fab")
		)
		(fp_line
			(start 0.67945 0.3048)
			(end 0.120396 0.3048)
			(stroke
				(width 0.1)
				(type default)
			)
			(layer "F.Fab")
		)
		(pad "1" smd circle
			(at -0.40005 0)
			(size 0 0)
			(layers "F.Cu" "F.Mask" "F.Paste")
			(net "FAN_3_FAULT_R")
		)
		(pad "2" smd circle
			(at 0.40005 0)
			(size 0 0)
			(layers "F.Cu" "F.Mask" "F.Paste")
			(net "FAN_3_P3V_R")
		)
	)
	(footprint ""
		(layer "F.Cu")
		(at 14.234922 -101.950012 180)
		(property "Reference" "R5198"
			(at 0 0 180)
			(layer "F.SilkS")
			(hide yes)
			(effects
				(font
					(size 1.27 1.27)
				)
			)
		)
		(property "Value" ""
			(at 0 0 180)
			(layer "F.Fab")
			(effects
				(font
					(size 1.27 1.27)
				)
			)
		)
		(duplicate_pad_numbers_are_jumpers no)
		(fp_line
			(start 0.7874 0.4064)
			(end -0.7874 0.4064)
			(stroke
				(width 0.1524)
				(type default)
			)
			(layer "F.SilkS")
		)
		(fp_line
			(start 0.7874 -0.4064)
			(end 0.7874 0.4064)
			(stroke
				(width 0.1524)
				(type default)
			)
			(layer "F.SilkS")
		)
		(fp_line
			(start -0.7874 0.4064)
			(end -0.7874 -0.4064)
			(stroke
				(width 0.1524)
				(type default)
			)
			(layer "F.SilkS")
		)
		(fp_line
			(start -0.7874 -0.4064)
			(end 0.7874 -0.4064)
			(stroke
				(width 0.1524)
				(type default)
			)
			(layer "F.SilkS")
		)
		(fp_line
			(start 0.67945 0.3048)
			(end 0.120396 0.3048)
			(stroke
				(width 0.1)
				(type default)
			)
			(layer "F.Fab")
		)
		(fp_line
			(start 0.67945 -0.3048)
			(end 0.67945 0.3048)
			(stroke
				(width 0.1)
				(type default)
			)
			(layer "F.Fab")
		)
		(fp_line
			(start 0.12065 -0.2794)
			(end 0.12065 -0.3048)
			(stroke
				(width 0.1)
				(type default)
			)
			(layer "F.Fab")
		)
		(fp_line
			(start 0.12065 -0.3048)
			(end 0.67945 -0.3048)
			(stroke
				(width 0.1)
				(type default)
			)
			(layer "F.Fab")
		)
		(fp_line
			(start 0.120396 0.3048)
			(end 0.120396 0.2794)
			(stroke
				(width 0.1)
				(type default)
			)
			(layer "F.Fab")
		)
		(fp_line
			(start 0.120396 0.2794)
			(end -0.12065 0.2794)
			(stroke
				(width 0.1)
				(type default)
			)
			(layer "F.Fab")
		)
		(fp_line
			(start -0.12065 0.3048)
			(end -0.67945 0.3048)
			(stroke
				(width 0.1)
				(type default)
			)
			(layer "F.Fab")
		)
		(fp_line
			(start -0.12065 0.2794)
			(end -0.12065 0.3048)
			(stroke
				(width 0.1)
				(type default)
			)
			(layer "F.Fab")
		)
		(fp_line
			(start -0.12065 -0.2794)
			(end 0.12065 -0.2794)
			(stroke
				(width 0.1)
				(type default)
			)
			(layer "F.Fab")
		)
		(fp_line
			(start -0.12065 -0.305054)
			(end -0.12065 -0.2794)
			(stroke
				(width 0.1)
				(type default)
			)
			(layer "F.Fab")
		)
		(fp_line
			(start -0.67945 0.3048)
			(end -0.67945 -0.305054)
			(stroke
				(width 0.1)
				(type default)
			)
			(layer "F.Fab")
		)
		(fp_line
			(start -0.67945 -0.305054)
			(end -0.12065 -0.305054)
			(stroke
				(width 0.1)
				(type default)
			)
			(layer "F.Fab")
		)
		(pad "1" smd circle
			(at -0.40005 0 180)
			(size 0 0)
			(layers "F.Cu" "F.Mask" "F.Paste")
			(net "FAN_5_PWM_OL")
		)
		(pad "2" smd circle
			(at 0.40005 0 180)
			(size 0 0)
			(layers "F.Cu" "F.Mask" "F.Paste")
			(net "FAN_5_PWM_OL_R")
		)
	)
)
